(kicad_pcb
	(version 20260206)
	(generator "pcbnew")
	(generator_version "10.0")
	(general
		(thickness 1.6)
		(legacy_teardrops no)
	)
	(paper "A4")
	(title_block
		(title "Bryce Canyon_IOM_M2_16342-2_OCP.brd")
		(comment 1 "Bryce Canyon / footprints 57-64 of 1146")
	)
	(layers
		(0 "F.Cu" signal "TOP")
		(4 "In1.Cu" signal "L2GND")
		(6 "In2.Cu" signal "L3")
		(8 "In3.Cu" signal "L4VCC")
		(10 "In4.Cu" signal "L5VCC")
		(12 "In5.Cu" signal "L6")
		(14 "In6.Cu" signal "L7GND")
		(2 "B.Cu" signal "BOTTOM")
		(9 "F.Adhes" user "F.Adhesive")
		(11 "B.Adhes" user "B.Adhesive")
		(13 "F.Paste" user "Package Geometry/Pastemask Top")
		(15 "B.Paste" user "Package Geometry/Pastemask Bottom")
		(5 "F.SilkS" user "Ref Des/Silkscreen Top")
		(7 "B.SilkS" user "Ref Des/Silkscreen Bottom")
		(1 "F.Mask" user "Board Geometry/Soldermask Top")
		(3 "B.Mask" user "Board Geometry/Soldermask Bottom")
		(17 "Dwgs.User" user "User.Drawings")
		(19 "Cmts.User" user "User.Comments")
		(21 "Eco1.User" user "User.Eco1")
		(23 "Eco2.User" user "User.Eco2")
		(25 "Edge.Cuts" user "Board Geometry/Outline")
		(27 "Margin" user)
		(31 "F.CrtYd" user "Package Geometry/Place Bound Top")
		(29 "B.CrtYd" user "Package Geometry/Place Bound Bottom")
		(35 "F.Fab" user "Ref Des/Assembly Top")
		(33 "B.Fab" user "Ref Des/Assembly Bottom")
	)
	(footprint ""
		(layer "F.Cu")
		(at 136.933432 -18.298414 180)
		(property "Reference" "C139"
			(at 0 0 180)
			(layer "F.SilkS")
			(hide yes)
			(effects
				(font
					(size 1.27 1.27)
				)
			)
		)
		(property "Value" "SCD1U50V3KX-GP"
			(at 0 -2.8194 180)
			(unlocked yes)
			(layer "F.Fab")
			(hide yes)
			(effects
				(font
					(size 1.016 1.016)
					(thickness 0.1524)
				)
			)
		)
		(property "Device Type" "C603H36"
			(at 0 -4.3434 180)
			(unlocked yes)
			(layer "F.Fab")
			(hide yes)
			(effects
				(font
					(size 1.016 1.016)
					(thickness 0.1524)
				)
			)
		)
		(duplicate_pad_numbers_are_jumpers no)
		(fp_line
			(start 0.508 0)
			(end -0.508 0)
			(stroke
				(width 0.2032)
				(type default)
			)
			(layer "F.SilkS")
		)
		(fp_rect
			(start -0.5842 1.3335)
			(end 0.5842 -1.3335)
			(stroke
				(width 0)
				(type default)
			)
			(fill no)
			(layer "F.CrtYd")
		)
		(fp_rect
			(start -0.5842 1.3335)
			(end 0.5842 -1.3335)
			(stroke
				(width 0)
				(type default)
			)
			(fill no)
			(layer "F.Fab")
		)
		(pad "1" smd custom
			(at 0 -0.762 180)
			(size 0.2159 0.2159)
			(layers "F.Cu" "F.Mask" "F.Paste")
			(net "P12V_IOM")
			(options
				(clearance outline)
				(anchor circle)
			)
			(primitives
				(gr_poly
					(pts
						(arc
							(start -0.3302 -0.4318)
							(mid -0.402042 -0.402042)
							(end -0.4318 -0.3302)
						)
						(arc
							(start -0.4318 0.3302)
							(mid -0.402042 0.402042)
							(end -0.3302 0.4318)
						)
						(arc
							(start 0.3302 0.4318)
							(mid 0.402042 0.402042)
							(end 0.4318 0.3302)
						)
						(arc
							(start 0.4318 -0.3302)
							(mid 0.402042 -0.402042)
							(end 0.3302 -0.4318)
						)
					)
					(width 0)
					(fill yes)
				)
			)
		)
		(pad "2" smd custom
			(at 0 0.762 180)
			(size 0.2159 0.2159)
			(layers "F.Cu" "F.Mask" "F.Paste")
			(net "GND")
			(options
				(clearance outline)
				(anchor circle)
			)
			(primitives
				(gr_poly
					(pts
						(arc
							(start -0.3302 -0.4318)
							(mid -0.402042 -0.402042)
							(end -0.4318 -0.3302)
						)
						(arc
							(start -0.4318 0.3302)
							(mid -0.402042 0.402042)
							(end -0.3302 0.4318)
						)
						(arc
							(start 0.3302 0.4318)
							(mid 0.402042 0.402042)
							(end 0.4318 0.3302)
						)
						(arc
							(start 0.4318 -0.3302)
							(mid 0.402042 -0.402042)
							(end 0.3302 -0.4318)
						)
					)
					(width 0)
					(fill yes)
				)
			)
		)
	)
	(footprint ""
		(layer "F.Cu")
		(at 188.1886 -140.6144)
		(property "Reference" "TP214"
			(at 0 0 0)
			(layer "F.SilkS")
			(hide yes)
			(effects
				(font
					(size 1.27 1.27)
				)
			)
		)
		(property "Value" "TPAD28-2-GP"
			(at -0.0127 -1.6637 0)
			(unlocked yes)
			(layer "F.Fab")
			(hide yes)
			(effects
				(font
					(size 1.016 1.016)
					(thickness 0.1524)
				)
			)
		)
		(property "Device Type" "TPAD28"
			(at -0.0127 -3.1877 0)
			(unlocked yes)
			(layer "F.Fab")
			(hide yes)
			(effects
				(font
					(size 1.016 1.016)
					(thickness 0.1524)
				)
			)
		)
		(duplicate_pad_numbers_are_jumpers no)
		(fp_poly
			(pts
				(arc
					(start 0.3556 0)
					(mid -0.3556 0)
					(end 0.3556 0)
				)
			)
			(stroke
				(width 0)
				(type default)
			)
			(fill no)
			(layer "F.CrtYd")
		)
		(fp_poly
			(pts
				(arc
					(start 0.6096 0)
					(mid -0.6096 0)
					(end 0.6096 0)
				)
			)
			(stroke
				(width 0)
				(type default)
			)
			(fill no)
			(layer "F.Fab")
		)
		(pad "1" smd circle
			(at 0 0)
			(size 0.7112 0.7112)
			(layers "F.Cu" "F.Mask" "F.Paste")
			(net "TP_M2_2_MFG_DAT")
		)
	)
	(footprint ""
		(layer "F.Cu")
		(at 92.501974 -57.368694 90)
		(property "Reference" "R727"
			(at 0 0 90)
			(layer "F.SilkS")
			(hide yes)
			(effects
				(font
					(size 1.27 1.27)
				)
			)
		)
		(property "Value" "0R2J-2-GP"
			(at 0.064008 -3.993896 90)
			(unlocked yes)
			(layer "F.Fab")
			(hide yes)
			(effects
				(font
					(size 1.016 1.016)
					(thickness 0.1524)
				)
			)
		)
		(property "Device Type" "R402H16"
			(at 0.064008 -5.517896 90)
			(unlocked yes)
			(layer "F.Fab")
			(hide yes)
			(effects
				(font
					(size 1.016 1.016)
					(thickness 0.1524)
				)
			)
		)
		(duplicate_pad_numbers_are_jumpers no)
		(fp_line
			(start 0.508 -0.9398)
			(end -0.508 -0.9398)
			(stroke
				(width 0.1524)
				(type default)
			)
			(layer "F.SilkS")
		)
		(fp_line
			(start -0.508 -0.9398)
			(end -0.508 0.9398)
			(stroke
				(width 0.1524)
				(type default)
			)
			(layer "F.SilkS")
		)
		(fp_rect
			(start -0.508 0.9398)
			(end 0.508 -0.9398)
			(stroke
				(width 0)
				(type default)
			)
			(fill no)
			(layer "F.CrtYd")
		)
		(fp_rect
			(start -0.508 0.9398)
			(end 0.508 -0.9398)
			(stroke
				(width 0)
				(type default)
			)
			(fill no)
			(layer "F.Fab")
		)
		(pad "1" smd custom
			(at 0 -0.4445 90)
			(size 0.1397 0.1397)
			(layers "F.Cu" "F.Mask" "F.Paste")
			(net "P3V3_EN_R")
			(options
				(clearance outline)
				(anchor circle)
			)
			(primitives
				(gr_poly
					(pts
						(arc
							(start -0.1778 -0.2794)
							(mid -0.249642 -0.249642)
							(end -0.2794 -0.1778)
						)
						(arc
							(start -0.2794 0.1778)
							(mid -0.249642 0.249642)
							(end -0.1778 0.2794)
						)
						(arc
							(start 0.1778 0.2794)
							(mid 0.249642 0.249642)
							(end 0.2794 0.1778)
						)
						(arc
							(start 0.2794 -0.1778)
							(mid 0.249642 -0.249642)
							(end 0.1778 -0.2794)
						)
					)
					(width 0)
					(fill yes)
				)
			)
		)
		(pad "2" smd custom
			(at 0 0.4445 90)
			(size 0.1397 0.1397)
			(layers "F.Cu" "F.Mask" "F.Paste")
			(net "P3V3_EN")
			(options
				(clearance outline)
				(anchor circle)
			)
			(primitives
				(gr_poly
					(pts
						(arc
							(start -0.1778 -0.2794)
							(mid -0.249642 -0.249642)
							(end -0.2794 -0.1778)
						)
						(arc
							(start -0.2794 0.1778)
							(mid -0.249642 0.249642)
							(end -0.1778 0.2794)
						)
						(arc
							(start 0.1778 0.2794)
							(mid 0.249642 0.249642)
							(end 0.2794 0.1778)
						)
						(arc
							(start 0.2794 -0.1778)
							(mid 0.249642 -0.249642)
							(end 0.1778 -0.2794)
						)
					)
					(width 0)
					(fill yes)
				)
			)
		)
	)
	(footprint ""
		(layer "F.Cu")
		(at 226.309936 -48.9712 -90)
		(property "Reference" "R469"
			(at 0 0 270)
			(layer "F.SilkS")
			(hide yes)
			(effects
				(font
					(size 1.27 1.27)
				)
			)
		)
		(property "Value" "3D01R5F-GP"
			(at 0 -8.9535 270)
			(unlocked yes)
			(layer "F.Fab")
			(hide yes)
			(effects
				(font
					(size 1.27 1.016)
					(thickness 0.1524)
				)
			)
		)
		(property "Device Type" "R805H24"
			(at 0 -10.6299 270)
			(unlocked yes)
			(layer "F.Fab")
			(hide yes)
			(effects
				(font
					(size 1.27 1.016)
					(thickness 0.1524)
				)
			)
		)
		(duplicate_pad_numbers_are_jumpers no)
		(fp_line
			(start -0.889 1.7018)
			(end 0.889 1.7018)
			(stroke
				(width 0.1524)
				(type default)
			)
			(layer "F.SilkS")
		)
		(fp_line
			(start 0.889 1.7018)
			(end 0.889 -0.508)
			(stroke
				(width 0.1524)
				(type default)
			)
			(layer "F.SilkS")
		)
		(fp_line
			(start -0.889 0.0762)
			(end -0.889 1.7018)
			(stroke
				(width 0.1524)
				(type default)
			)
			(layer "F.SilkS")
		)
		(fp_line
			(start -0.889 -1.7018)
			(end -0.889 0.2794)
			(stroke
				(width 0.1524)
				(type default)
			)
			(layer "F.SilkS")
		)
		(fp_line
			(start 0.889 -1.7018)
			(end 0.889 -0.381)
			(stroke
				(width 0.1524)
				(type default)
			)
			(layer "F.SilkS")
		)
		(fp_line
			(start 0.889 -1.7018)
			(end -0.889 -1.7018)
			(stroke
				(width 0.1524)
				(type default)
			)
			(layer "F.SilkS")
		)
		(fp_poly
			(pts
				(xy 0.9652 -1.778) (xy 0.9652 1.778) (xy -0.9652 1.778) (xy -0.9652 -1.778)
			)
			(stroke
				(width 0)
				(type default)
			)
			(fill no)
			(layer "F.CrtYd")
		)
		(fp_rect
			(start -0.9652 1.778)
			(end 0.9652 -1.778)
			(stroke
				(width 0)
				(type default)
			)
			(fill no)
			(layer "F.Fab")
		)
		(pad "1" smd rect
			(at 0 -0.9652 270)
			(size 1.397 1.143)
			(layers "F.Cu" "F.Mask" "F.Paste")
			(net "P5V_SNB")
		)
		(pad "2" smd rect
			(at 0 0.9652 270)
			(size 1.397 1.143)
			(layers "F.Cu" "F.Mask" "F.Paste")
			(net "GND")
		)
	)
	(footprint ""
		(layer "F.Cu")
		(at 49.657 -128.143 180)
		(property "Reference" "R287"
			(at 0 0 180)
			(layer "F.SilkS")
			(hide yes)
			(effects
				(font
					(size 1.27 1.27)
				)
			)
		)
		(property "Value" "0R2J-2-GP"
			(at 0.064008 -3.993896 180)
			(unlocked yes)
			(layer "F.Fab")
			(hide yes)
			(effects
				(font
					(size 1.016 1.016)
					(thickness 0.1524)
				)
			)
		)
		(property "Device Type" "R402H16"
			(at 0.064008 -5.517896 180)
			(unlocked yes)
			(layer "F.Fab")
			(hide yes)
			(effects
				(font
					(size 1.016 1.016)
					(thickness 0.1524)
				)
			)
		)
		(duplicate_pad_numbers_are_jumpers no)
		(fp_line
			(start 0.508 -0.9398)
			(end -0.508 -0.9398)
			(stroke
				(width 0.1524)
				(type default)
			)
			(layer "F.SilkS")
		)
		(fp_line
			(start -0.508 -0.9398)
			(end -0.508 0.9398)
			(stroke
				(width 0.1524)
				(type default)
			)
			(layer "F.SilkS")
		)
		(fp_rect
			(start -0.508 0.9398)
			(end 0.508 -0.9398)
			(stroke
				(width 0)
				(type default)
			)
			(fill no)
			(layer "F.CrtYd")
		)
		(fp_rect
			(start -0.508 0.9398)
			(end 0.508 -0.9398)
			(stroke
				(width 0)
				(type default)
			)
			(fill no)
			(layer "F.Fab")
		)
		(pad "1" smd custom
			(at 0 -0.4445 180)
			(size 0.1397 0.1397)
			(layers "F.Cu" "F.Mask" "F.Paste")
			(net "SCC_RMT_FULL_PWR_EN")
			(options
				(clearance outline)
				(anchor circle)
			)
			(primitives
				(gr_poly
					(pts
						(arc
							(start -0.1778 -0.2794)
							(mid -0.249642 -0.249642)
							(end -0.2794 -0.1778)
						)
						(arc
							(start -0.2794 0.1778)
							(mid -0.249642 0.249642)
							(end -0.1778 0.2794)
						)
						(arc
							(start 0.1778 0.2794)
							(mid 0.249642 0.249642)
							(end 0.2794 0.1778)
						)
						(arc
							(start 0.2794 -0.1778)
							(mid 0.249642 -0.249642)
							(end 0.1778 -0.2794)
						)
					)
					(width 0)
					(fill yes)
				)
			)
		)
		(pad "2" smd custom
			(at 0 0.4445 180)
			(size 0.1397 0.1397)
			(layers "F.Cu" "F.Mask" "F.Paste")
			(net "SCC_RMT_FULLPWR_EN")
			(options
				(clearance outline)
				(anchor circle)
			)
			(primitives
				(gr_poly
					(pts
						(arc
							(start -0.1778 -0.2794)
							(mid -0.249642 -0.249642)
							(end -0.2794 -0.1778)
						)
						(arc
							(start -0.2794 0.1778)
							(mid -0.249642 0.249642)
							(end -0.1778 0.2794)
						)
						(arc
							(start 0.1778 0.2794)
							(mid 0.249642 0.249642)
							(end 0.2794 0.1778)
						)
						(arc
							(start 0.2794 -0.1778)
							(mid 0.249642 -0.249642)
							(end 0.1778 -0.2794)
						)
					)
					(width 0)
					(fill yes)
				)
			)
		)
	)
	(footprint ""
		(layer "F.Cu")
		(at 149.999954 -120.000014)
		(property "Reference" ""
			(at 0 0 0)
			(layer "F.SilkS")
			(hide yes)
			(effects
				(font
					(size 1.27 1.27)
				)
			)
		)
		(property "Value" "*"
			(at -6.38175 0.19685 0)
			(unlocked yes)
			(layer "F.Fab")
			(hide yes)
			(effects
				(font
					(size 1.016 1.016)
					(thickness 0.1524)
				)
			)
		)
		(duplicate_pad_numbers_are_jumpers no)
		(fp_poly
			(pts
				(arc
					(start 5.0673 0)
					(mid -5.0673 0)
					(end 5.0673 0)
				)
			)
			(stroke
				(width 0)
				(type default)
			)
			(fill no)
			(layer "B.CrtYd")
		)
		(fp_poly
			(pts
				(arc
					(start 5.0673 0)
					(mid -5.0673 0)
					(end 5.0673 0)
				)
			)
			(stroke
				(width 0)
				(type default)
			)
			(fill no)
			(layer "F.CrtYd")
		)
		(fp_poly
			(pts
				(arc
					(start 5.0673 0)
					(mid -5.0673 0)
					(end 5.0673 0)
				)
			)
			(stroke
				(width 0)
				(type default)
			)
			(fill no)
			(layer "B.Fab")
		)
		(fp_poly
			(pts
				(arc
					(start 5.0673 0)
					(mid -5.0673 0)
					(end 5.0673 0)
				)
			)
			(stroke
				(width 0)
				(type default)
			)
			(fill no)
			(layer "F.Fab")
		)
		(pad "1" thru_hole circle
			(at 0 0)
			(size 9.525 9.525)
			(drill 3.5052)
			(layers "*.Cu" "*.Mask")
			(remove_unused_layers no)
			(net "Net_43")
			(clearance -2.5019)
			(thermal_gap 0.3048)
			(padstack
				(mode front_inner_back)
				(layer "Inner"
					(shape circle)
					(size 3.9116 3.9116)
					(clearance 0.3048)
				)
				(layer "B.Cu"
					(shape circle)
					(size 9.525 9.525)
					(clearance -2.5019)
				)
			)
		)
	)
	(footprint ""
		(layer "F.Cu")
		(at 38.321488 -161.399728)
		(property "Reference" "R299"
			(at 0 0 0)
			(layer "F.SilkS")
			(hide yes)
			(effects
				(font
					(size 1.27 1.27)
				)
			)
		)
		(property "Value" "4K7R2F-GP"
			(at 0.064008 -3.993896 0)
			(unlocked yes)
			(layer "F.Fab")
			(hide yes)
			(effects
				(font
					(size 1.016 1.016)
					(thickness 0.1524)
				)
			)
		)
		(property "Device Type" "R402H16"
			(at 0.064008 -5.517896 0)
			(unlocked yes)
			(layer "F.Fab")
			(hide yes)
			(effects
				(font
					(size 1.016 1.016)
					(thickness 0.1524)
				)
			)
		)
		(duplicate_pad_numbers_are_jumpers no)
		(fp_line
			(start -0.508 -0.9398)
			(end -0.508 0.9398)
			(stroke
				(width 0.1524)
				(type default)
			)
			(layer "F.SilkS")
		)
		(fp_line
			(start 0.508 -0.9398)
			(end -0.508 -0.9398)
			(stroke
				(width 0.1524)
				(type default)
			)
			(layer "F.SilkS")
		)
		(fp_rect
			(start -0.508 0.9398)
			(end 0.508 -0.9398)
			(stroke
				(width 0)
				(type default)
			)
			(fill no)
			(layer "F.CrtYd")
		)
		(fp_rect
			(start -0.508 0.9398)
			(end 0.508 -0.9398)
			(stroke
				(width 0)
				(type default)
			)
			(fill no)
			(layer "F.Fab")
		)
		(pad "1" smd custom
			(at 0 -0.4445)
			(size 0.1397 0.1397)
			(layers "F.Cu" "F.Mask" "F.Paste")
			(net "P3V3_STBY")
			(options
				(clearance outline)
				(anchor circle)
			)
			(primitives
				(gr_poly
					(pts
						(arc
							(start -0.1778 -0.2794)
							(mid -0.249642 -0.249642)
							(end -0.2794 -0.1778)
						)
						(arc
							(start -0.2794 0.1778)
							(mid -0.249642 0.249642)
							(end -0.1778 0.2794)
						)
						(arc
							(start 0.1778 0.2794)
							(mid 0.249642 0.249642)
							(end 0.2794 0.1778)
						)
						(arc
							(start 0.2794 -0.1778)
							(mid 0.249642 -0.249642)
							(end 0.1778 -0.2794)
						)
					)
					(width 0)
					(fill yes)
				)
			)
		)
		(pad "2" smd custom
			(at 0 0.4445)
			(size 0.1397 0.1397)
			(layers "F.Cu" "F.Mask" "F.Paste")
			(net "UART_BMC_COMP_IN_RX")
			(options
				(clearance outline)
				(anchor circle)
			)
			(primitives
				(gr_poly
					(pts
						(arc
							(start -0.1778 -0.2794)
							(mid -0.249642 -0.249642)
							(end -0.2794 -0.1778)
						)
						(arc
							(start -0.2794 0.1778)
							(mid -0.249642 0.249642)
							(end -0.1778 0.2794)
						)
						(arc
							(start 0.1778 0.2794)
							(mid 0.249642 0.249642)
							(end 0.2794 0.1778)
						)
						(arc
							(start 0.2794 -0.1778)
							(mid 0.249642 -0.249642)
							(end 0.1778 -0.2794)
						)
					)
					(width 0)
					(fill yes)
				)
			)
		)
	)
	(footprint ""
		(layer "F.Cu")
		(at 97.282 -147.8534 180)
		(property "Reference" "R29"
			(at 0 0 180)
			(layer "F.SilkS")
			(hide yes)
			(effects
				(font
					(size 1.27 1.27)
				)
			)
		)
		(property "Value" "4K7R2F-GP"
			(at 0.064008 -3.993896 180)
			(unlocked yes)
			(layer "F.Fab")
			(hide yes)
			(effects
				(font
					(size 1.016 1.016)
					(thickness 0.1524)
				)
			)
		)
		(property "Device Type" "R402H16"
			(at 0.064008 -5.517896 180)
			(unlocked yes)
			(layer "F.Fab")
			(hide yes)
			(effects
				(font
					(size 1.016 1.016)
					(thickness 0.1524)
				)
			)
		)
		(duplicate_pad_numbers_are_jumpers no)
		(fp_line
			(start 0.508 -0.9398)
			(end -0.508 -0.9398)
			(stroke
				(width 0.1524)
				(type default)
			)
			(layer "F.SilkS")
		)
		(fp_line
			(start -0.508 -0.9398)
			(end -0.508 0.9398)
			(stroke
				(width 0.1524)
				(type default)
			)
			(layer "F.SilkS")
		)
		(fp_rect
			(start -0.508 0.9398)
			(end 0.508 -0.9398)
			(stroke
				(width 0)
				(type default)
			)
			(fill no)
			(layer "F.CrtYd")
		)
		(fp_rect
			(start -0.508 0.9398)
			(end 0.508 -0.9398)
			(stroke
				(width 0)
				(type default)
			)
			(fill no)
			(layer "F.Fab")
		)
		(pad "1" smd custom
			(at 0 -0.4445 180)
			(size 0.1397 0.1397)
			(layers "F.Cu" "F.Mask" "F.Paste")
			(net "P3V3_STBY")
			(options
				(clearance outline)
				(anchor circle)
			)
			(primitives
				(gr_poly
					(pts
						(arc
							(start -0.1778 -0.2794)
							(mid -0.249642 -0.249642)
							(end -0.2794 -0.1778)
						)
						(arc
							(start -0.2794 0.1778)
							(mid -0.249642 0.249642)
							(end -0.1778 0.2794)
						)
						(arc
							(start 0.1778 0.2794)
							(mid 0.249642 0.249642)
							(end 0.2794 0.1778)
						)
						(arc
							(start 0.2794 -0.1778)
							(mid 0.249642 -0.249642)
							(end 0.1778 -0.2794)
						)
					)
					(width 0)
					(fill yes)
				)
			)
		)
		(pad "2" smd custom
			(at 0 0.4445 180)
			(size 0.1397 0.1397)
			(layers "F.Cu" "F.Mask" "F.Paste")
			(net "USB_OCS_N2")
			(options
				(clearance outline)
				(anchor circle)
			)
			(primitives
				(gr_poly
					(pts
						(arc
							(start -0.1778 -0.2794)
							(mid -0.249642 -0.249642)
							(end -0.2794 -0.1778)
						)
						(arc
							(start -0.2794 0.1778)
							(mid -0.249642 0.249642)
							(end -0.1778 0.2794)
						)
						(arc
							(start 0.1778 0.2794)
							(mid 0.249642 0.249642)
							(end 0.2794 0.1778)
						)
						(arc
							(start 0.2794 -0.1778)
							(mid 0.249642 -0.249642)
							(end 0.1778 -0.2794)
						)
					)
					(width 0)
					(fill yes)
				)
			)
		)
	)
)
